(kicad_pcb
	(version 20241229)
	(generator "pcbnew")
	(generator_version "9.0")
	(general
		(thickness 1.62)
		(legacy_teardrops no)
	)
	(paper "A3")
	(title_block
		(title "COM Express 7 Baseboard")
		(date "2025-02-04")
		(rev "1.1.2")
		(company "Antmicro Ltd")
		(comment 1 "www.antmicro.com")
		(comment 9 "footprints 597-601 of 802")
	)
	(layers
		(0 "F.Cu" signal)
		(4 "In1.Cu" signal)
		(6 "In2.Cu" signal)
		(8 "In3.Cu" signal)
		(10 "In4.Cu" signal)
		(12 "In5.Cu" signal)
		(14 "In6.Cu" signal)
		(2 "B.Cu" signal)
		(9 "F.Adhes" user "F.Adhesive")
		(11 "B.Adhes" user "B.Adhesive")
		(13 "F.Paste" user)
		(15 "B.Paste" user)
		(5 "F.SilkS" user "F.Silkscreen")
		(7 "B.SilkS" user "B.Silkscreen")
		(1 "F.Mask" user)
		(3 "B.Mask" user)
		(17 "Dwgs.User" user "User.Drawings")
		(19 "Cmts.User" user "User.Comments")
		(21 "Eco1.User" user "User.Eco1")
		(23 "Eco2.User" user "User.Eco2")
		(25 "Edge.Cuts" user)
		(27 "Margin" user)
		(31 "F.CrtYd" user "F.Courtyard")
		(29 "B.CrtYd" user "B.Courtyard")
		(35 "F.Fab" user)
		(33 "B.Fab" user)
	)
	(footprint "antmicro-footprints:R_0402_1005Metric"
		(layer "B.Cu")
		(at 144.25 140.06)
		(descr "Resistor SMD 0402")
		(tags "resistor SMD 0402")
		(property "Reference" "R255"
			(at -1.45 5.4 0)
			(layer "B.SilkS")
			(effects
				(font
					(size 0.7 0.7)
					(thickness 0.15)
				)
				(justify right bottom mirror)
			)
		)
		(property "Value" "R_10k_0402"
			(at -1.011843 -1.772047 0)
			(layer "B.Fab")
			(effects
				(font
					(size 0.7 0.7)
					(thickness 0.15)
				)
				(justify right bottom mirror)
			)
		)
		(property "Datasheet" "https://www.bourns.com/docs/product-datasheets/cr.pdf"
			(at 0 0 0)
			(layer "F.Fab")
			(hide yes)
			(effects
				(font
					(size 1.27 1.27)
					(thickness 0.15)
				)
			)
		)
		(property "Author" "Antmicro"
			(at 0 0 0)
			(layer "B.Fab")
			(hide yes)
			(effects
				(font
					(size 1 1)
					(thickness 0.15)
				)
				(justify mirror)
			)
		)
		(property "License" "Apache-2.0"
			(at 0 0 0)
			(layer "B.Fab")
			(hide yes)
			(effects
				(font
					(size 1 1)
					(thickness 0.15)
				)
				(justify mirror)
			)
		)
		(property "MPN" "CR0402-FX-1002GLF"
			(at 0 0 0)
			(layer "B.Fab")
			(hide yes)
			(effects
				(font
					(size 1 1)
					(thickness 0.15)
				)
				(justify mirror)
			)
		)
		(property "Manufacturer" "Bourns"
			(at 0 0 0)
			(layer "B.Fab")
			(hide yes)
			(effects
				(font
					(size 1 1)
					(thickness 0.15)
				)
				(justify mirror)
			)
		)
		(property "Public" "False"
			(at 0 0 0)
			(layer "B.Fab")
			(hide yes)
			(effects
				(font
					(size 1 1)
					(thickness 0.15)
				)
				(justify mirror)
			)
		)
		(property "Tolerance" "1%"
			(at 0 0 0)
			(layer "B.Fab")
			(hide yes)
			(effects
				(font
					(size 1 1)
					(thickness 0.15)
				)
				(justify mirror)
			)
		)
		(property "Val" "10k"
			(at 0 0 0)
			(layer "B.Fab")
			(hide yes)
			(effects
				(font
					(size 1 1)
					(thickness 0.15)
				)
				(justify mirror)
			)
		)
		(sheetname "KR to SFI #1")
		(sheetfile "kr_sfi.kicad_sch")
		(attr smd)
		(fp_rect
			(start -0.925 0.47)
			(end 0.925 -0.47)
			(stroke
				(width 0.05)
				(type default)
			)
			(fill no)
			(layer "B.CrtYd")
		)
		(fp_rect
			(start -0.5 0.25)
			(end 0.5 -0.25)
			(stroke
				(width 0.15)
				(type solid)
			)
			(fill no)
			(layer "B.Fab")
		)
		(pad "1" smd roundrect
			(at -0.48 0)
			(size 0.59 0.64)
			(layers "B.Cu" "B.Mask" "B.Paste")
			(roundrect_rratio 0.25)
			(net 1 "GND")
			(pintype "passive")
			(teardrops
				(best_length_ratio 0.2)
				(max_length 1)
				(best_width_ratio 0.9)
				(max_width 2)
				(curved_edges yes)
				(filter_ratio 0.9)
				(enabled yes)
				(allow_two_segments yes)
				(prefer_zone_connections yes)
			)
		)
		(pad "2" smd roundrect
			(at 0.48 0)
			(size 0.59 0.64)
			(layers "B.Cu" "B.Mask" "B.Paste")
			(roundrect_rratio 0.25)
			(net 653 "Net-(U43C-TESTEN)")
			(pintype "passive")
			(teardrops
				(best_length_ratio 0.2)
				(max_length 1)
				(best_width_ratio 0.9)
				(max_width 2)
				(curved_edges yes)
				(filter_ratio 0.9)
				(enabled yes)
				(allow_two_segments yes)
				(prefer_zone_connections yes)
			)
		)
	)
	(footprint "antmicro-footprints:C_0402_1005Metric"
		(layer "B.Cu")
		(at 107.893 164.377 180)
		(descr "Capacitor SMD 0402")
		(tags "capacitor SMD 0402")
		(property "Reference" "C145"
			(at -3.707 -0.003 0)
			(layer "B.SilkS")
			(effects
				(font
					(size 0.7 0.7)
					(thickness 0.15)
				)
				(justify left bottom mirror)
			)
		)
		(property "Value" "C_220n_0402"
			(at -1.022927 -2.155213 0)
			(layer "B.Fab")
			(effects
				(font
					(size 0.7 0.7)
					(thickness 0.15)
				)
				(justify left bottom mirror)
			)
		)
		(property "Datasheet" "https://www.yageo.com/en/Chart/Download/pdf/CC0402KRX5R6BB224"
			(at 0 0 180)
			(layer "F.Fab")
			(hide yes)
			(effects
				(font
					(size 1.27 1.27)
					(thickness 0.15)
				)
			)
		)
		(property "Author" "Antmicro"
			(at 215.786 328.754 0)
			(layer "B.Fab")
			(hide yes)
			(effects
				(font
					(size 1 1)
					(thickness 0.15)
				)
				(justify mirror)
			)
		)
		(property "Dielectric" ""
			(at 215.786 328.754 0)
			(layer "B.Fab")
			(hide yes)
			(effects
				(font
					(size 1 1)
					(thickness 0.15)
				)
				(justify mirror)
			)
		)
		(property "License" "Apache-2.0"
			(at 215.786 328.754 0)
			(layer "B.Fab")
			(hide yes)
			(effects
				(font
					(size 1 1)
					(thickness 0.15)
				)
				(justify mirror)
			)
		)
		(property "MPN" "CC0402KRX5R6BB224"
			(at 215.786 328.754 0)
			(layer "B.Fab")
			(hide yes)
			(effects
				(font
					(size 1 1)
					(thickness 0.15)
				)
				(justify mirror)
			)
		)
		(property "Manufacturer" "YAGEO"
			(at 215.786 328.754 0)
			(layer "B.Fab")
			(hide yes)
			(effects
				(font
					(size 1 1)
					(thickness 0.15)
				)
				(justify mirror)
			)
		)
		(property "Public" "False"
			(at 215.786 328.754 0)
			(layer "B.Fab")
			(hide yes)
			(effects
				(font
					(size 1 1)
					(thickness 0.15)
				)
				(justify mirror)
			)
		)
		(property "Val" "220n"
			(at 215.786 328.754 0)
			(layer "B.Fab")
			(hide yes)
			(effects
				(font
					(size 1 1)
					(thickness 0.15)
				)
				(justify mirror)
			)
		)
		(property "Voltage" ""
			(at 215.786 328.754 0)
			(layer "B.Fab")
			(hide yes)
			(effects
				(font
					(size 1 1)
					(thickness 0.15)
				)
				(justify mirror)
			)
		)
		(sheetname "PCIe redriver")
		(sheetfile "pcie_redriver.kicad_sch")
		(attr smd)
		(fp_rect
			(start -0.925 0.47)
			(end 0.925 -0.47)
			(stroke
				(width 0.05)
				(type default)
			)
			(fill no)
			(layer "B.CrtYd")
		)
		(fp_line
			(start 0.504 0.25)
			(end -0.494 0.25)
			(stroke
				(width 0.15)
				(type solid)
			)
			(layer "B.Fab")
		)
		(fp_line
			(start 0.504 -0.248)
			(end 0.504 0.25)
			(stroke
				(width 0.15)
				(type solid)
			)
			(layer "B.Fab")
		)
		(fp_line
			(start -0.494 0.25)
			(end -0.494 -0.248)
			(stroke
				(width 0.15)
				(type solid)
			)
			(layer "B.Fab")
		)
		(fp_line
			(start -0.494 -0.248)
			(end 0.504 -0.248)
			(stroke
				(width 0.15)
				(type solid)
			)
			(layer "B.Fab")
		)
		(pad "1" smd roundrect
			(at -0.48 0 180)
			(size 0.59 0.64)
			(layers "B.Cu" "B.Mask" "B.Paste")
			(roundrect_rratio 0.25)
			(net 965 "/PCIe redriver/PCIe_{O}_C.TX1-")
			(pintype "passive")
			(teardrops
				(best_length_ratio 0.2)
				(max_length 1)
				(best_width_ratio 0.9)
				(max_width 2)
				(curved_edges yes)
				(filter_ratio 0.9)
				(enabled yes)
				(allow_two_segments yes)
				(prefer_zone_connections yes)
			)
		)
		(pad "2" smd roundrect
			(at 0.48 0 180)
			(size 0.59 0.64)
			(layers "B.Cu" "B.Mask" "B.Paste")
			(roundrect_rratio 0.25)
			(net 96 "/OCuLink/PCIe_{x4}.TX1-")
			(pintype "passive")
			(teardrops
				(best_length_ratio 0.2)
				(max_length 1)
				(best_width_ratio 0.9)
				(max_width 2)
				(curved_edges yes)
				(filter_ratio 0.9)
				(enabled yes)
				(allow_two_segments yes)
				(prefer_zone_connections yes)
			)
		)
	)
	(footprint "antmicro-footprints:R_0402_1005Metric"
		(layer "B.Cu")
		(at 146.95 136.06)
		(descr "Resistor SMD 0402")
		(tags "resistor SMD 0402")
		(property "Reference" "R266"
			(at -1.3 -0.5 0)
			(layer "B.SilkS")
			(effects
				(font
					(size 0.7 0.7)
					(thickness 0.15)
				)
				(justify right bottom mirror)
			)
		)
		(property "Value" "R_10k_0402"
			(at -1.011843 -1.772047 0)
			(layer "B.Fab")
			(effects
				(font
					(size 0.7 0.7)
					(thickness 0.15)
				)
				(justify right bottom mirror)
			)
		)
		(property "Datasheet" "https://www.bourns.com/docs/product-datasheets/cr.pdf"
			(at 0 0 0)
			(layer "F.Fab")
			(hide yes)
			(effects
				(font
					(size 1.27 1.27)
					(thickness 0.15)
				)
			)
		)
		(property "Author" "Antmicro"
			(at 0 0 0)
			(layer "B.Fab")
			(hide yes)
			(effects
				(font
					(size 1 1)
					(thickness 0.15)
				)
				(justify mirror)
			)
		)
		(property "License" "Apache-2.0"
			(at 0 0 0)
			(layer "B.Fab")
			(hide yes)
			(effects
				(font
					(size 1 1)
					(thickness 0.15)
				)
				(justify mirror)
			)
		)
		(property "MPN" "CR0402-FX-1002GLF"
			(at 0 0 0)
			(layer "B.Fab")
			(hide yes)
			(effects
				(font
					(size 1 1)
					(thickness 0.15)
				)
				(justify mirror)
			)
		)
		(property "Manufacturer" "Bourns"
			(at 0 0 0)
			(layer "B.Fab")
			(hide yes)
			(effects
				(font
					(size 1 1)
					(thickness 0.15)
				)
				(justify mirror)
			)
		)
		(property "Public" "False"
			(at 0 0 0)
			(layer "B.Fab")
			(hide yes)
			(effects
				(font
					(size 1 1)
					(thickness 0.15)
				)
				(justify mirror)
			)
		)
		(property "Tolerance" "1%"
			(at 0 0 0)
			(layer "B.Fab")
			(hide yes)
			(effects
				(font
					(size 1 1)
					(thickness 0.15)
				)
				(justify mirror)
			)
		)
		(property "Val" "10k"
			(at 0 0 0)
			(layer "B.Fab")
			(hide yes)
			(effects
				(font
					(size 1 1)
					(thickness 0.15)
				)
				(justify mirror)
			)
		)
		(sheetname "KR to SFI #1")
		(sheetfile "kr_sfi.kicad_sch")
		(attr smd)
		(fp_rect
			(start -0.925 0.47)
			(end 0.925 -0.47)
			(stroke
				(width 0.05)
				(type default)
			)
			(fill no)
			(layer "B.CrtYd")
		)
		(fp_rect
			(start -0.5 0.25)
			(end 0.5 -0.25)
			(stroke
				(width 0.15)
				(type solid)
			)
			(fill no)
			(layer "B.Fab")
		)
		(pad "1" smd roundrect
			(at -0.48 0)
			(size 0.59 0.64)
			(layers "B.Cu" "B.Mask" "B.Paste")
			(roundrect_rratio 0.25)
			(net 1 "GND")
			(pintype "passive")
			(teardrops
				(best_length_ratio 0.2)
				(max_length 1)
				(best_width_ratio 0.9)
				(max_width 2)
				(curved_edges yes)
				(filter_ratio 0.9)
				(enabled yes)
				(allow_two_segments yes)
				(prefer_zone_connections yes)
			)
		)
		(pad "2" smd roundrect
			(at 0.48 0)
			(size 0.59 0.64)
			(layers "B.Cu" "B.Mask" "B.Paste")
			(roundrect_rratio 0.25)
			(net 659 "Net-(U43C-PRTAD3)")
			(pintype "passive")
			(teardrops
				(best_length_ratio 0.2)
				(max_length 1)
				(best_width_ratio 0.9)
				(max_width 2)
				(curved_edges yes)
				(filter_ratio 0.9)
				(enabled yes)
				(allow_two_segments yes)
				(prefer_zone_connections yes)
			)
		)
	)
	(footprint "antmicro-footprints:C_0402_1005Metric"
		(layer "B.Cu")
		(at 130.5 169.435 180)
		(descr "Capacitor SMD 0402")
		(tags "capacitor SMD 0402")
		(property "Reference" "C210"
			(at -1.4 0.525 0)
			(layer "B.SilkS")
			(effects
				(font
					(size 0.7 0.7)
					(thickness 0.15)
				)
				(justify left bottom mirror)
			)
		)
		(property "Value" "C_100n_0402"
			(at -1.022927 -2.155213 0)
			(layer "B.Fab")
			(effects
				(font
					(size 0.7 0.7)
					(thickness 0.15)
				)
				(justify left bottom mirror)
			)
		)
		(property "Datasheet" "https://www.murata.com/products/productdetail?partno=GRM155R61H104KE14%23"
			(at 0 0 180)
			(layer "F.Fab")
			(hide yes)
			(effects
				(font
					(size 1.27 1.27)
					(thickness 0.15)
				)
			)
		)
		(property "Author" "Antmicro"
			(at 261 338.87 0)
			(layer "B.Fab")
			(hide yes)
			(effects
				(font
					(size 1 1)
					(thickness 0.15)
				)
				(justify mirror)
			)
		)
		(property "Dielectric" "X5R"
			(at 261 338.87 0)
			(layer "B.Fab")
			(hide yes)
			(effects
				(font
					(size 1 1)
					(thickness 0.15)
				)
				(justify mirror)
			)
		)
		(property "License" "Apache-2.0"
			(at 261 338.87 0)
			(layer "B.Fab")
			(hide yes)
			(effects
				(font
					(size 1 1)
					(thickness 0.15)
				)
				(justify mirror)
			)
		)
		(property "MPN" "GRM155R61H104KE14D"
			(at 261 338.87 0)
			(layer "B.Fab")
			(hide yes)
			(effects
				(font
					(size 1 1)
					(thickness 0.15)
				)
				(justify mirror)
			)
		)
		(property "Manufacturer" "Murata"
			(at 261 338.87 0)
			(layer "B.Fab")
			(hide yes)
			(effects
				(font
					(size 1 1)
					(thickness 0.15)
				)
				(justify mirror)
			)
		)
		(property "Public" "False"
			(at 261 338.87 0)
			(layer "B.Fab")
			(hide yes)
			(effects
				(font
					(size 1 1)
					(thickness 0.15)
				)
				(justify mirror)
			)
		)
		(property "Val" "100n"
			(at 261 338.87 0)
			(layer "B.Fab")
			(hide yes)
			(effects
				(font
					(size 1 1)
					(thickness 0.15)
				)
				(justify mirror)
			)
		)
		(property "Voltage" "50V"
			(at 261 338.87 0)
			(layer "B.Fab")
			(hide yes)
			(effects
				(font
					(size 1 1)
					(thickness 0.15)
				)
				(justify mirror)
			)
		)
		(sheetname "2xSFP+")
		(sheetfile "2xSFP+.kicad_sch")
		(attr smd)
		(fp_rect
			(start -0.925 0.47)
			(end 0.925 -0.47)
			(stroke
				(width 0.05)
				(type default)
			)
			(fill no)
			(layer "B.CrtYd")
		)
		(fp_line
			(start 0.504 0.25)
			(end -0.494 0.25)
			(stroke
				(width 0.15)
				(type solid)
			)
			(layer "B.Fab")
		)
		(fp_line
			(start 0.504 -0.248)
			(end 0.504 0.25)
			(stroke
				(width 0.15)
				(type solid)
			)
			(layer "B.Fab")
		)
		(fp_line
			(start -0.494 0.25)
			(end -0.494 -0.248)
			(stroke
				(width 0.15)
				(type solid)
			)
			(layer "B.Fab")
		)
		(fp_line
			(start -0.494 -0.248)
			(end 0.504 -0.248)
			(stroke
				(width 0.15)
				(type solid)
			)
			(layer "B.Fab")
		)
		(pad "1" smd roundrect
			(at -0.48 0 180)
			(size 0.59 0.64)
			(layers "B.Cu" "B.Mask" "B.Paste")
			(roundrect_rratio 0.25)
			(net 53 "/2xSFP+/SH")
			(pintype "passive")
			(teardrops
				(best_length_ratio 0.2)
				(max_length 1)
				(best_width_ratio 0.9)
				(max_width 2)
				(curved_edges yes)
				(filter_ratio 0.9)
				(enabled yes)
				(allow_two_segments yes)
				(prefer_zone_connections yes)
			)
		)
		(pad "2" smd roundrect
			(at 0.48 0 180)
			(size 0.59 0.64)
			(layers "B.Cu" "B.Mask" "B.Paste")
			(roundrect_rratio 0.25)
			(net 1 "GND")
			(pintype "passive")
			(teardrops
				(best_length_ratio 0.2)
				(max_length 1)
				(best_width_ratio 0.9)
				(max_width 2)
				(curved_edges yes)
				(filter_ratio 0.9)
				(enabled yes)
				(allow_two_segments yes)
				(prefer_zone_connections yes)
			)
		)
	)
	(footprint "antmicro-footprints:C_0402_1005Metric"
		(layer "B.Cu")
		(at 122.55 169.435 180)
		(descr "Capacitor SMD 0402")
		(tags "capacitor SMD 0402")
		(property "Reference" "C209"
			(at -1.2 0.525 0)
			(layer "B.SilkS")
			(effects
				(font
					(size 0.7 0.7)
					(thickness 0.15)
				)
				(justify left bottom mirror)
			)
		)
		(property "Value" "C_100n_0402"
			(at -1.022927 -2.155213 0)
			(layer "B.Fab")
			(effects
				(font
					(size 0.7 0.7)
					(thickness 0.15)
				)
				(justify left bottom mirror)
			)
		)
		(property "Datasheet" "https://www.murata.com/products/productdetail?partno=GRM155R61H104KE14%23"
			(at 0 0 180)
			(layer "F.Fab")
			(hide yes)
			(effects
				(font
					(size 1.27 1.27)
					(thickness 0.15)
				)
			)
		)
		(property "Author" "Antmicro"
			(at 245.1 338.87 0)
			(layer "B.Fab")
			(hide yes)
			(effects
				(font
					(size 1 1)
					(thickness 0.15)
				)
				(justify mirror)
			)
		)
		(property "Dielectric" "X5R"
			(at 245.1 338.87 0)
			(layer "B.Fab")
			(hide yes)
			(effects
				(font
					(size 1 1)
					(thickness 0.15)
				)
				(justify mirror)
			)
		)
		(property "License" "Apache-2.0"
			(at 245.1 338.87 0)
			(layer "B.Fab")
			(hide yes)
			(effects
				(font
					(size 1 1)
					(thickness 0.15)
				)
				(justify mirror)
			)
		)
		(property "MPN" "GRM155R61H104KE14D"
			(at 245.1 338.87 0)
			(layer "B.Fab")
			(hide yes)
			(effects
				(font
					(size 1 1)
					(thickness 0.15)
				)
				(justify mirror)
			)
		)
		(property "Manufacturer" "Murata"
			(at 245.1 338.87 0)
			(layer "B.Fab")
			(hide yes)
			(effects
				(font
					(size 1 1)
					(thickness 0.15)
				)
				(justify mirror)
			)
		)
		(property "Public" "False"
			(at 245.1 338.87 0)
			(layer "B.Fab")
			(hide yes)
			(effects
				(font
					(size 1 1)
					(thickness 0.15)
				)
				(justify mirror)
			)
		)
		(property "Val" "100n"
			(at 245.1 338.87 0)
			(layer "B.Fab")
			(hide yes)
			(effects
				(font
					(size 1 1)
					(thickness 0.15)
				)
				(justify mirror)
			)
		)
		(property "Voltage" "50V"
			(at 245.1 338.87 0)
			(layer "B.Fab")
			(hide yes)
			(effects
				(font
					(size 1 1)
					(thickness 0.15)
				)
				(justify mirror)
			)
		)
		(sheetname "2xSFP+")
		(sheetfile "2xSFP+.kicad_sch")
		(attr smd)
		(fp_rect
			(start -0.925 0.47)
			(end 0.925 -0.47)
			(stroke
				(width 0.05)
				(type default)
			)
			(fill no)
			(layer "B.CrtYd")
		)
		(fp_line
			(start 0.504 0.25)
			(end -0.494 0.25)
			(stroke
				(width 0.15)
				(type solid)
			)
			(layer "B.Fab")
		)
		(fp_line
			(start 0.504 -0.248)
			(end 0.504 0.25)
			(stroke
				(width 0.15)
				(type solid)
			)
			(layer "B.Fab")
		)
		(fp_line
			(start -0.494 0.25)
			(end -0.494 -0.248)
			(stroke
				(width 0.15)
				(type solid)
			)
			(layer "B.Fab")
		)
		(fp_line
			(start -0.494 -0.248)
			(end 0.504 -0.248)
			(stroke
				(width 0.15)
				(type solid)
			)
			(layer "B.Fab")
		)
		(pad "1" smd roundrect
			(at -0.48 0 180)
			(size 0.59 0.64)
			(layers "B.Cu" "B.Mask" "B.Paste")
			(roundrect_rratio 0.25)
			(net 53 "/2xSFP+/SH")
			(pintype "passive")
			(teardrops
				(best_length_ratio 0.2)
				(max_length 1)
				(best_width_ratio 0.9)
				(max_width 2)
				(curved_edges yes)
				(filter_ratio 0.9)
				(enabled yes)
				(allow_two_segments yes)
				(prefer_zone_connections yes)
			)
		)
		(pad "2" smd roundrect
			(at 0.48 0 180)
			(size 0.59 0.64)
			(layers "B.Cu" "B.Mask" "B.Paste")
			(roundrect_rratio 0.25)
			(net 1 "GND")
			(pintype "passive")
			(teardrops
				(best_length_ratio 0.2)
				(max_length 1)
				(best_width_ratio 0.9)
				(max_width 2)
				(curved_edges yes)
				(filter_ratio 0.9)
				(enabled yes)
				(allow_two_segments yes)
				(prefer_zone_connections yes)
			)
		)
	)
)
